(kicad_pcb
	(version 20260206)
	(generator "pcbnew")
	(generator_version "10.0")
	(general
		(thickness 1.6)
		(legacy_teardrops no)
	)
	(paper "A4")
	(title_block
		(title "03242023_DA0F0TMBIJ0_F0T_Motherboard_J_brd_V01_OCP.brd")
		(comment 1 "Grand Teton / footprints 1942-1948 of 6105")
	)
	(layers
		(0 "F.Cu" signal "TOP")
		(4 "In1.Cu" signal "GND")
		(6 "In2.Cu" signal "IN1")
		(8 "In3.Cu" signal "GND1")
		(10 "In4.Cu" signal "IN2")
		(12 "In5.Cu" signal "GND2")
		(14 "In6.Cu" signal "IN3")
		(16 "In7.Cu" signal "GND3")
		(18 "In8.Cu" signal "VCC")
		(20 "In9.Cu" signal "VCC1")
		(22 "In10.Cu" signal "GND4")
		(24 "In11.Cu" signal "IN4")
		(26 "In12.Cu" signal "GND5")
		(28 "In13.Cu" signal "IN5")
		(30 "In14.Cu" signal "GND6")
		(32 "In15.Cu" signal "IN6")
		(34 "In16.Cu" signal "GND7")
		(2 "B.Cu" signal "BOTTOM")
		(9 "F.Adhes" user "F.Adhesive")
		(11 "B.Adhes" user "B.Adhesive")
		(13 "F.Paste" user "Package Geometry/Pastemask Top")
		(15 "B.Paste" user "Package Geometry/Pastemask Bottom")
		(5 "F.SilkS" user "Ref Des/Silkscreen Top")
		(7 "B.SilkS" user "Ref Des/Silkscreen Bottom")
		(1 "F.Mask" user "Board Geometry/Soldermask Top")
		(3 "B.Mask" user "Board Geometry/Soldermask Bottom")
		(17 "Dwgs.User" user "User.Drawings")
		(19 "Cmts.User" user "User.Comments")
		(21 "Eco1.User" user "User.Eco1")
		(23 "Eco2.User" user "User.Eco2")
		(25 "Edge.Cuts" user "Board Geometry/Outline")
		(27 "Margin" user)
		(31 "F.CrtYd" user "Package Geometry/Place Bound Top")
		(29 "B.CrtYd" user "Package Geometry/Place Bound Bottom")
		(35 "F.Fab" user "Ref Des/Assembly Top")
		(33 "B.Fab" user "Ref Des/Assembly Bottom")
	)
	(footprint ""
		(layer "F.Cu")
		(at 170.732958 -358.698292)
		(property "Reference" "PR225"
			(at 0 0 0)
			(layer "F.SilkS")
			(hide yes)
			(effects
				(font
					(size 1.27 1.27)
				)
			)
		)
		(property "Value" ""
			(at 0 0 0)
			(layer "F.Fab")
			(effects
				(font
					(size 1.27 1.27)
				)
			)
		)
		(duplicate_pad_numbers_are_jumpers no)
		(fp_line
			(start -0.7874 -0.4064)
			(end 0.7874 -0.4064)
			(stroke
				(width 0.1524)
				(type default)
			)
			(layer "F.SilkS")
		)
		(fp_line
			(start -0.7874 0.4064)
			(end -0.7874 -0.4064)
			(stroke
				(width 0.1524)
				(type default)
			)
			(layer "F.SilkS")
		)
		(fp_line
			(start 0.7874 -0.4064)
			(end 0.7874 0.4064)
			(stroke
				(width 0.1524)
				(type default)
			)
			(layer "F.SilkS")
		)
		(fp_line
			(start 0.7874 0.4064)
			(end -0.7874 0.4064)
			(stroke
				(width 0.1524)
				(type default)
			)
			(layer "F.SilkS")
		)
		(fp_line
			(start -0.67945 -0.305054)
			(end -0.12065 -0.305054)
			(stroke
				(width 0.1)
				(type default)
			)
			(layer "F.Fab")
		)
		(fp_line
			(start -0.67945 0.3048)
			(end -0.67945 -0.305054)
			(stroke
				(width 0.1)
				(type default)
			)
			(layer "F.Fab")
		)
		(fp_line
			(start -0.12065 -0.305054)
			(end -0.12065 -0.2794)
			(stroke
				(width 0.1)
				(type default)
			)
			(layer "F.Fab")
		)
		(fp_line
			(start -0.12065 -0.2794)
			(end 0.12065 -0.2794)
			(stroke
				(width 0.1)
				(type default)
			)
			(layer "F.Fab")
		)
		(fp_line
			(start -0.12065 0.2794)
			(end -0.12065 0.3048)
			(stroke
				(width 0.1)
				(type default)
			)
			(layer "F.Fab")
		)
		(fp_line
			(start -0.12065 0.3048)
			(end -0.67945 0.3048)
			(stroke
				(width 0.1)
				(type default)
			)
			(layer "F.Fab")
		)
		(fp_line
			(start 0.120396 0.2794)
			(end -0.12065 0.2794)
			(stroke
				(width 0.1)
				(type default)
			)
			(layer "F.Fab")
		)
		(fp_line
			(start 0.120396 0.3048)
			(end 0.120396 0.2794)
			(stroke
				(width 0.1)
				(type default)
			)
			(layer "F.Fab")
		)
		(fp_line
			(start 0.12065 -0.3048)
			(end 0.67945 -0.3048)
			(stroke
				(width 0.1)
				(type default)
			)
			(layer "F.Fab")
		)
		(fp_line
			(start 0.12065 -0.2794)
			(end 0.12065 -0.3048)
			(stroke
				(width 0.1)
				(type default)
			)
			(layer "F.Fab")
		)
		(fp_line
			(start 0.67945 -0.3048)
			(end 0.67945 0.3048)
			(stroke
				(width 0.1)
				(type default)
			)
			(layer "F.Fab")
		)
		(fp_line
			(start 0.67945 0.3048)
			(end 0.120396 0.3048)
			(stroke
				(width 0.1)
				(type default)
			)
			(layer "F.Fab")
		)
		(pad "1" smd circle
			(at -0.40005 0)
			(size 0 0)
			(layers "F.Cu" "F.Mask" "F.Paste")
			(net "PVCCFA_EHV_FIVRA_CPU1_LSET1")
		)
		(pad "2" smd circle
			(at 0.40005 0)
			(size 0 0)
			(layers "F.Cu" "F.Mask" "F.Paste")
			(net "GND")
		)
	)
	(footprint ""
		(layer "F.Cu")
		(at 160.83788 -104.485948)
		(property "Reference" "R2846"
			(at 0 0 0)
			(layer "F.SilkS")
			(hide yes)
			(effects
				(font
					(size 1.27 1.27)
				)
			)
		)
		(property "Value" ""
			(at 0 0 0)
			(layer "F.Fab")
			(effects
				(font
					(size 1.27 1.27)
				)
			)
		)
		(duplicate_pad_numbers_are_jumpers no)
		(fp_line
			(start -0.7874 -0.4064)
			(end 0.7874 -0.4064)
			(stroke
				(width 0.1524)
				(type default)
			)
			(layer "F.SilkS")
		)
		(fp_line
			(start -0.7874 0.4064)
			(end -0.7874 -0.4064)
			(stroke
				(width 0.1524)
				(type default)
			)
			(layer "F.SilkS")
		)
		(fp_line
			(start 0.7874 -0.4064)
			(end 0.7874 0.4064)
			(stroke
				(width 0.1524)
				(type default)
			)
			(layer "F.SilkS")
		)
		(fp_line
			(start 0.7874 0.4064)
			(end -0.7874 0.4064)
			(stroke
				(width 0.1524)
				(type default)
			)
			(layer "F.SilkS")
		)
		(fp_line
			(start -0.67945 -0.305054)
			(end -0.12065 -0.305054)
			(stroke
				(width 0.1)
				(type default)
			)
			(layer "F.Fab")
		)
		(fp_line
			(start -0.67945 0.3048)
			(end -0.67945 -0.305054)
			(stroke
				(width 0.1)
				(type default)
			)
			(layer "F.Fab")
		)
		(fp_line
			(start -0.12065 -0.305054)
			(end -0.12065 -0.2794)
			(stroke
				(width 0.1)
				(type default)
			)
			(layer "F.Fab")
		)
		(fp_line
			(start -0.12065 -0.2794)
			(end 0.12065 -0.2794)
			(stroke
				(width 0.1)
				(type default)
			)
			(layer "F.Fab")
		)
		(fp_line
			(start -0.12065 0.2794)
			(end -0.12065 0.3048)
			(stroke
				(width 0.1)
				(type default)
			)
			(layer "F.Fab")
		)
		(fp_line
			(start -0.12065 0.3048)
			(end -0.67945 0.3048)
			(stroke
				(width 0.1)
				(type default)
			)
			(layer "F.Fab")
		)
		(fp_line
			(start 0.120396 0.2794)
			(end -0.12065 0.2794)
			(stroke
				(width 0.1)
				(type default)
			)
			(layer "F.Fab")
		)
		(fp_line
			(start 0.120396 0.3048)
			(end 0.120396 0.2794)
			(stroke
				(width 0.1)
				(type default)
			)
			(layer "F.Fab")
		)
		(fp_line
			(start 0.12065 -0.3048)
			(end 0.67945 -0.3048)
			(stroke
				(width 0.1)
				(type default)
			)
			(layer "F.Fab")
		)
		(fp_line
			(start 0.12065 -0.2794)
			(end 0.12065 -0.3048)
			(stroke
				(width 0.1)
				(type default)
			)
			(layer "F.Fab")
		)
		(fp_line
			(start 0.67945 -0.3048)
			(end 0.67945 0.3048)
			(stroke
				(width 0.1)
				(type default)
			)
			(layer "F.Fab")
		)
		(fp_line
			(start 0.67945 0.3048)
			(end 0.120396 0.3048)
			(stroke
				(width 0.1)
				(type default)
			)
			(layer "F.Fab")
		)
		(pad "1" smd circle
			(at -0.40005 0)
			(size 0 0)
			(layers "F.Cu" "F.Mask" "F.Paste")
			(net "BIC_MONITER_ISO")
		)
		(pad "2" smd circle
			(at 0.40005 0)
			(size 0 0)
			(layers "F.Cu" "F.Mask" "F.Paste")
			(net "BIC_MONITER_ISO_R")
		)
	)
	(footprint ""
		(layer "F.Cu")
		(at 19.19859 -385.065524 -90)
		(property "Reference" "R4661"
			(at 0 0 270)
			(layer "F.SilkS")
			(hide yes)
			(effects
				(font
					(size 1.27 1.27)
				)
			)
		)
		(property "Value" ""
			(at 0 0 270)
			(layer "F.Fab")
			(effects
				(font
					(size 1.27 1.27)
				)
			)
		)
		(duplicate_pad_numbers_are_jumpers no)
		(fp_line
			(start -0.7874 0.4064)
			(end -0.7874 -0.4064)
			(stroke
				(width 0.1524)
				(type default)
			)
			(layer "F.SilkS")
		)
		(fp_line
			(start 0.7874 0.4064)
			(end -0.7874 0.4064)
			(stroke
				(width 0.1524)
				(type default)
			)
			(layer "F.SilkS")
		)
		(fp_line
			(start 0.029464 -0.4064)
			(end 0.7874 -0.4064)
			(stroke
				(width 0.1524)
				(type default)
			)
			(layer "F.SilkS")
		)
		(fp_line
			(start -0.67945 0.3048)
			(end -0.67945 -0.305054)
			(stroke
				(width 0.1)
				(type default)
			)
			(layer "F.Fab")
		)
		(fp_line
			(start -0.12065 0.3048)
			(end -0.67945 0.3048)
			(stroke
				(width 0.1)
				(type default)
			)
			(layer "F.Fab")
		)
		(fp_line
			(start 0.120396 0.3048)
			(end 0.120396 0.2794)
			(stroke
				(width 0.1)
				(type default)
			)
			(layer "F.Fab")
		)
		(fp_line
			(start 0.67945 0.3048)
			(end 0.120396 0.3048)
			(stroke
				(width 0.1)
				(type default)
			)
			(layer "F.Fab")
		)
		(fp_line
			(start -0.12065 0.2794)
			(end -0.12065 0.3048)
			(stroke
				(width 0.1)
				(type default)
			)
			(layer "F.Fab")
		)
		(fp_line
			(start 0.120396 0.2794)
			(end -0.12065 0.2794)
			(stroke
				(width 0.1)
				(type default)
			)
			(layer "F.Fab")
		)
		(fp_line
			(start -0.12065 -0.2794)
			(end 0.12065 -0.2794)
			(stroke
				(width 0.1)
				(type default)
			)
			(layer "F.Fab")
		)
		(fp_line
			(start 0.12065 -0.2794)
			(end 0.12065 -0.3048)
			(stroke
				(width 0.1)
				(type default)
			)
			(layer "F.Fab")
		)
		(fp_line
			(start 0.12065 -0.3048)
			(end 0.67945 -0.3048)
			(stroke
				(width 0.1)
				(type default)
			)
			(layer "F.Fab")
		)
		(fp_line
			(start 0.67945 -0.3048)
			(end 0.67945 0.3048)
			(stroke
				(width 0.1)
				(type default)
			)
			(layer "F.Fab")
		)
		(fp_line
			(start -0.67945 -0.305054)
			(end -0.12065 -0.305054)
			(stroke
				(width 0.1)
				(type default)
			)
			(layer "F.Fab")
		)
		(fp_line
			(start -0.12065 -0.305054)
			(end -0.12065 -0.2794)
			(stroke
				(width 0.1)
				(type default)
			)
			(layer "F.Fab")
		)
		(pad "1" smd rect
			(at -0.40005 0 90)
			(size 0.4572 0.508)
			(layers "F.Cu" "F.Mask" "F.Paste")
			(net "P2E_MB_BMC_TX_C_DP<0>")
		)
		(pad "2" smd rect
			(at 0.40005 0 90)
			(size 0.4572 0.508)
			(layers "F.Cu" "F.Mask" "F.Paste")
			(net "P2E_MB_BMC_TX_C_R2_DP<0>")
		)
	)
	(footprint ""
		(layer "F.Cu")
		(at 377.54052 -109.720888)
		(property "Reference" "R2512"
			(at 0 0 0)
			(layer "F.SilkS")
			(hide yes)
			(effects
				(font
					(size 1.27 1.27)
				)
			)
		)
		(property "Value" ""
			(at 0 0 0)
			(layer "F.Fab")
			(effects
				(font
					(size 1.27 1.27)
				)
			)
		)
		(duplicate_pad_numbers_are_jumpers no)
		(fp_line
			(start -0.7874 -0.4064)
			(end 0.7874 -0.4064)
			(stroke
				(width 0.1524)
				(type default)
			)
			(layer "F.SilkS")
		)
		(fp_line
			(start -0.7874 0.4064)
			(end -0.7874 -0.4064)
			(stroke
				(width 0.1524)
				(type default)
			)
			(layer "F.SilkS")
		)
		(fp_line
			(start 0.7874 -0.4064)
			(end 0.7874 0.4064)
			(stroke
				(width 0.1524)
				(type default)
			)
			(layer "F.SilkS")
		)
		(fp_line
			(start 0.7874 0.4064)
			(end -0.7874 0.4064)
			(stroke
				(width 0.1524)
				(type default)
			)
			(layer "F.SilkS")
		)
		(fp_line
			(start -0.67945 -0.305054)
			(end -0.12065 -0.305054)
			(stroke
				(width 0.1)
				(type default)
			)
			(layer "F.Fab")
		)
		(fp_line
			(start -0.67945 0.3048)
			(end -0.67945 -0.305054)
			(stroke
				(width 0.1)
				(type default)
			)
			(layer "F.Fab")
		)
		(fp_line
			(start -0.12065 -0.305054)
			(end -0.12065 -0.2794)
			(stroke
				(width 0.1)
				(type default)
			)
			(layer "F.Fab")
		)
		(fp_line
			(start -0.12065 -0.2794)
			(end 0.12065 -0.2794)
			(stroke
				(width 0.1)
				(type default)
			)
			(layer "F.Fab")
		)
		(fp_line
			(start -0.12065 0.2794)
			(end -0.12065 0.3048)
			(stroke
				(width 0.1)
				(type default)
			)
			(layer "F.Fab")
		)
		(fp_line
			(start -0.12065 0.3048)
			(end -0.67945 0.3048)
			(stroke
				(width 0.1)
				(type default)
			)
			(layer "F.Fab")
		)
		(fp_line
			(start 0.120396 0.2794)
			(end -0.12065 0.2794)
			(stroke
				(width 0.1)
				(type default)
			)
			(layer "F.Fab")
		)
		(fp_line
			(start 0.120396 0.3048)
			(end 0.120396 0.2794)
			(stroke
				(width 0.1)
				(type default)
			)
			(layer "F.Fab")
		)
		(fp_line
			(start 0.12065 -0.3048)
			(end 0.67945 -0.3048)
			(stroke
				(width 0.1)
				(type default)
			)
			(layer "F.Fab")
		)
		(fp_line
			(start 0.12065 -0.2794)
			(end 0.12065 -0.3048)
			(stroke
				(width 0.1)
				(type default)
			)
			(layer "F.Fab")
		)
		(fp_line
			(start 0.67945 -0.3048)
			(end 0.67945 0.3048)
			(stroke
				(width 0.1)
				(type default)
			)
			(layer "F.Fab")
		)
		(fp_line
			(start 0.67945 0.3048)
			(end 0.120396 0.3048)
			(stroke
				(width 0.1)
				(type default)
			)
			(layer "F.Fab")
		)
		(pad "1" smd circle
			(at -0.40005 0)
			(size 0 0)
			(layers "F.Cu" "F.Mask" "F.Paste")
			(net "P1V05_PCH_AUX")
		)
		(pad "2" smd circle
			(at 0.40005 0)
			(size 0 0)
			(layers "F.Cu" "F.Mask" "F.Paste")
			(net "P0V7_JTAG_VREF_2")
		)
	)
	(footprint ""
		(layer "F.Cu")
		(at 396.81785 -402.371052 -90)
		(property "Reference" "C950"
			(at 0 0 270)
			(layer "F.SilkS")
			(hide yes)
			(effects
				(font
					(size 1.27 1.27)
				)
			)
		)
		(property "Value" ""
			(at 0 0 270)
			(layer "F.Fab")
			(effects
				(font
					(size 1.27 1.27)
				)
			)
		)
		(duplicate_pad_numbers_are_jumpers no)
		(fp_line
			(start -0.299974 0.150114)
			(end -0.299974 -0.150114)
			(stroke
				(width 0.1)
				(type default)
			)
			(layer "F.Fab")
		)
		(fp_line
			(start 0.299974 0.150114)
			(end -0.299974 0.150114)
			(stroke
				(width 0.1)
				(type default)
			)
			(layer "F.Fab")
		)
		(fp_line
			(start -0.299974 -0.150114)
			(end 0.299974 -0.150114)
			(stroke
				(width 0.1)
				(type default)
			)
			(layer "F.Fab")
		)
		(fp_line
			(start 0.299974 -0.150114)
			(end 0.299974 0.150114)
			(stroke
				(width 0.1)
				(type default)
			)
			(layer "F.Fab")
		)
		(pad "1" smd rect
			(at -0.2667 0 270)
			(size 0.3048 0.381)
			(layers "F.Cu" "F.Mask" "F.Paste")
			(net "P5E_CPU0_PE2_TX_C_DN<7>")
		)
		(pad "2" smd rect
			(at 0.2667 0 270)
			(size 0.3048 0.381)
			(layers "F.Cu" "F.Mask" "F.Paste")
			(net "P5E_CPU0_PE2_TX_DN<7>")
		)
	)
	(footprint ""
		(layer "F.Cu")
		(at 373.577358 -92.962984 90)
		(property "Reference" "R480"
			(at 0 0 90)
			(layer "F.SilkS")
			(hide yes)
			(effects
				(font
					(size 1.27 1.27)
				)
			)
		)
		(property "Value" ""
			(at 0 0 90)
			(layer "F.Fab")
			(effects
				(font
					(size 1.27 1.27)
				)
			)
		)
		(duplicate_pad_numbers_are_jumpers no)
		(fp_line
			(start 0.7874 -0.4064)
			(end 0.7874 0.4064)
			(stroke
				(width 0.1524)
				(type default)
			)
			(layer "F.SilkS")
		)
		(fp_line
			(start -0.7874 -0.4064)
			(end 0.7874 -0.4064)
			(stroke
				(width 0.1524)
				(type default)
			)
			(layer "F.SilkS")
		)
		(fp_line
			(start 0.7874 0.4064)
			(end -0.7874 0.4064)
			(stroke
				(width 0.1524)
				(type default)
			)
			(layer "F.SilkS")
		)
		(fp_line
			(start -0.7874 0.4064)
			(end -0.7874 -0.4064)
			(stroke
				(width 0.1524)
				(type default)
			)
			(layer "F.SilkS")
		)
		(fp_line
			(start -0.12065 -0.305054)
			(end -0.12065 -0.2794)
			(stroke
				(width 0.1)
				(type default)
			)
			(layer "F.Fab")
		)
		(fp_line
			(start -0.67945 -0.305054)
			(end -0.12065 -0.305054)
			(stroke
				(width 0.1)
				(type default)
			)
			(layer "F.Fab")
		)
		(fp_line
			(start 0.67945 -0.3048)
			(end 0.67945 0.3048)
			(stroke
				(width 0.1)
				(type default)
			)
			(layer "F.Fab")
		)
		(fp_line
			(start 0.12065 -0.3048)
			(end 0.67945 -0.3048)
			(stroke
				(width 0.1)
				(type default)
			)
			(layer "F.Fab")
		)
		(fp_line
			(start 0.12065 -0.2794)
			(end 0.12065 -0.3048)
			(stroke
				(width 0.1)
				(type default)
			)
			(layer "F.Fab")
		)
		(fp_line
			(start -0.12065 -0.2794)
			(end 0.12065 -0.2794)
			(stroke
				(width 0.1)
				(type default)
			)
			(layer "F.Fab")
		)
		(fp_line
			(start 0.120396 0.2794)
			(end -0.12065 0.2794)
			(stroke
				(width 0.1)
				(type default)
			)
			(layer "F.Fab")
		)
		(fp_line
			(start -0.12065 0.2794)
			(end -0.12065 0.3048)
			(stroke
				(width 0.1)
				(type default)
			)
			(layer "F.Fab")
		)
		(fp_line
			(start 0.67945 0.3048)
			(end 0.120396 0.3048)
			(stroke
				(width 0.1)
				(type default)
			)
			(layer "F.Fab")
		)
		(fp_line
			(start 0.120396 0.3048)
			(end 0.120396 0.2794)
			(stroke
				(width 0.1)
				(type default)
			)
			(layer "F.Fab")
		)
		(fp_line
			(start -0.12065 0.3048)
			(end -0.67945 0.3048)
			(stroke
				(width 0.1)
				(type default)
			)
			(layer "F.Fab")
		)
		(fp_line
			(start -0.67945 0.3048)
			(end -0.67945 -0.305054)
			(stroke
				(width 0.1)
				(type default)
			)
			(layer "F.Fab")
		)
		(pad "1" smd circle
			(at -0.40005 0 90)
			(size 0 0)
			(layers "F.Cu" "F.Mask" "F.Paste")
			(net "JTAG_DBP_TMS")
		)
		(pad "2" smd circle
			(at 0.40005 0 90)
			(size 0 0)
			(layers "F.Cu" "F.Mask" "F.Paste")
			(net "JTAG_DBP_FB_TMS")
		)
	)
	(footprint ""
		(layer "F.Cu")
		(at 420.682166 -135.146034 180)
		(property "Reference" "PC221"
			(at 0 0 180)
			(layer "F.SilkS")
			(hide yes)
			(effects
				(font
					(size 1.27 1.27)
				)
			)
		)
		(property "Value" ""
			(at 0 0 180)
			(layer "F.Fab")
			(effects
				(font
					(size 1.27 1.27)
				)
			)
		)
		(duplicate_pad_numbers_are_jumpers no)
		(fp_line
			(start 0.7874 0.4064)
			(end -0.7874 0.4064)
			(stroke
				(width 0.1524)
				(type default)
			)
			(layer "F.SilkS")
		)
		(fp_line
			(start 0.7874 -0.4064)
			(end 0.7874 0.4064)
			(stroke
				(width 0.1524)
				(type default)
			)
			(layer "F.SilkS")
		)
		(fp_line
			(start -0.7874 0.4064)
			(end -0.7874 -0.4064)
			(stroke
				(width 0.1524)
				(type default)
			)
			(layer "F.SilkS")
		)
		(fp_line
			(start -0.7874 -0.4064)
			(end 0.7874 -0.4064)
			(stroke
				(width 0.1524)
				(type default)
			)
			(layer "F.SilkS")
		)
		(fp_line
			(start 0.67945 0.3048)
			(end 0.120396 0.3048)
			(stroke
				(width 0.1)
				(type default)
			)
			(layer "F.Fab")
		)
		(fp_line
			(start 0.67945 -0.3048)
			(end 0.67945 0.3048)
			(stroke
				(width 0.1)
				(type default)
			)
			(layer "F.Fab")
		)
		(fp_line
			(start 0.12065 -0.2794)
			(end 0.12065 -0.3048)
			(stroke
				(width 0.1)
				(type default)
			)
			(layer "F.Fab")
		)
		(fp_line
			(start 0.12065 -0.3048)
			(end 0.67945 -0.3048)
			(stroke
				(width 0.1)
				(type default)
			)
			(layer "F.Fab")
		)
		(fp_line
			(start 0.120396 0.3048)
			(end 0.120396 0.2794)
			(stroke
				(width 0.1)
				(type default)
			)
			(layer "F.Fab")
		)
		(fp_line
			(start 0.120396 0.2794)
			(end -0.12065 0.2794)
			(stroke
				(width 0.1)
				(type default)
			)
			(layer "F.Fab")
		)
		(fp_line
			(start -0.12065 0.3048)
			(end -0.67945 0.3048)
			(stroke
				(width 0.1)
				(type default)
			)
			(layer "F.Fab")
		)
		(fp_line
			(start -0.12065 0.2794)
			(end -0.12065 0.3048)
			(stroke
				(width 0.1)
				(type default)
			)
			(layer "F.Fab")
		)
		(fp_line
			(start -0.12065 -0.2794)
			(end 0.12065 -0.2794)
			(stroke
				(width 0.1)
				(type default)
			)
			(layer "F.Fab")
		)
		(fp_line
			(start -0.12065 -0.305054)
			(end -0.12065 -0.2794)
			(stroke
				(width 0.1)
				(type default)
			)
			(layer "F.Fab")
		)
		(fp_line
			(start -0.67945 0.3048)
			(end -0.67945 -0.305054)
			(stroke
				(width 0.1)
				(type default)
			)
			(layer "F.Fab")
		)
		(fp_line
			(start -0.67945 -0.305054)
			(end -0.12065 -0.305054)
			(stroke
				(width 0.1)
				(type default)
			)
			(layer "F.Fab")
		)
		(pad "1" smd circle
			(at -0.40005 0 180)
			(size 0 0)
			(layers "F.Cu" "F.Mask" "F.Paste")
			(net "PVCCINFAON_CPU0_VIN_CSNIN")
		)
		(pad "2" smd circle
			(at 0.40005 0 180)
			(size 0 0)
			(layers "F.Cu" "F.Mask" "F.Paste")
			(net "GND")
		)
	)
)
